# T6G (Grand Teton) — schematic netlist excerpt (pin names and nets, part order shuffled) for the footprints in the layout excerpt that follows; sources: Cadence DE-HDL packaged netlist, KiCad conversion of 04192023_DAF0TMB3IC0_F0TG_MB_C_brd_V02_OCP.brd

R1898  Q_RES  100 1% CHIP  pkg 0402LF  page 132 : A = OCP_SFF_ISO_BIF2_EN ; B = GND
PR260  Q_RES  0 5% CHIP  pkg 0402LF  page 218 : A = PVDDCR_CPU1_P1_VOS2 ; B = PVDDCR_CPU1_P1

(kicad_pcb
	(version 20260206)
	(generator "pcbnew")
	(generator_version "10.0")
	(general
		(thickness 1.6)
		(legacy_teardrops no)
	)
	(paper "A4")
	(title_block
		(title "04192023_DAF0TMB3IC0_F0TG_MB_C_brd_V02_OCP.brd")
		(comment 1 "Grand Teton / footprints 7663-7664 of 8354")
	)
	(layers
		(0 "F.Cu" signal "TOP")
		(4 "In1.Cu" signal "GND")
		(6 "In2.Cu" signal "IN1")
		(8 "In3.Cu" signal "GND1")
		(10 "In4.Cu" signal "IN2")
		(12 "In5.Cu" signal "GND2")
		(14 "In6.Cu" signal "IN3")
		(16 "In7.Cu" signal "GND3")
		(18 "In8.Cu" signal "VCC")
		(20 "In9.Cu" signal "VCC1")
		(22 "In10.Cu" signal "GND4")
		(24 "In11.Cu" signal "IN4")
		(26 "In12.Cu" signal "GND5")
		(28 "In13.Cu" signal "IN5")
		(30 "In14.Cu" signal "GND6")
		(32 "In15.Cu" signal "IN6")
		(34 "In16.Cu" signal "GND7")
		(2 "B.Cu" signal "BOTTOM")
		(9 "F.Adhes" user "F.Adhesive")
		(11 "B.Adhes" user "B.Adhesive")
		(13 "F.Paste" user "Package Geometry/Pastemask Top")
		(15 "B.Paste" user "Package Geometry/Pastemask Bottom")
		(5 "F.SilkS" user "Ref Des/Silkscreen Top")
		(7 "B.SilkS" user "Ref Des/Silkscreen Bottom")
		(1 "F.Mask" user "Board Geometry/Soldermask Top")
		(3 "B.Mask" user "Board Geometry/Soldermask Bottom")
		(17 "Dwgs.User" user "User.Drawings")
		(19 "Cmts.User" user "User.Comments")
		(21 "Eco1.User" user "User.Eco1")
		(23 "Eco2.User" user "User.Eco2")
		(25 "Edge.Cuts" user "Board Geometry/Outline")
		(27 "Margin" user)
		(31 "F.CrtYd" user "Package Geometry/Place Bound Top")
		(29 "B.CrtYd" user "Package Geometry/Place Bound Bottom")
		(35 "F.Fab" user "Ref Des/Assembly Top")
		(33 "B.Fab" user "Ref Des/Assembly Bottom")
	)
	(footprint ""
		(layer "B.Cu")
		(at 75.103228 -337.658202 -90)
		(property "Reference" "PR260"
			(at 0 0 90)
			(layer "B.SilkS")
			(hide yes)
			(effects
				(font
					(size 1.27 1.27)
				)
				(justify mirror)
			)
		)
		(property "Value" ""
			(at 0 0 90)
			(layer "B.Fab")
			(effects
				(font
					(size 1.27 1.27)
				)
				(justify mirror)
			)
		)
		(duplicate_pad_numbers_are_jumpers no)
		(fp_line
			(start -0.7874 0.4064)
			(end 0.7874 0.4064)
			(stroke
				(width 0.1524)
				(type default)
			)
			(layer "B.SilkS")
		)
		(fp_line
			(start 0.7874 0.4064)
			(end 0.7874 -0.4064)
			(stroke
				(width 0.1524)
				(type default)
			)
			(layer "B.SilkS")
		)
		(fp_line
			(start -0.7874 -0.4064)
			(end -0.7874 0.4064)
			(stroke
				(width 0.1524)
				(type default)
			)
			(layer "B.SilkS")
		)
		(fp_line
			(start 0.7874 -0.4064)
			(end -0.7874 -0.4064)
			(stroke
				(width 0.1524)
				(type default)
			)
			(layer "B.SilkS")
		)
		(fp_line
			(start -0.67945 0.3048)
			(end -0.120396 0.3048)
			(stroke
				(width 0.1)
				(type default)
			)
			(layer "B.Fab")
		)
		(fp_line
			(start -0.120396 0.3048)
			(end -0.120396 0.2794)
			(stroke
				(width 0.1)
				(type default)
			)
			(layer "B.Fab")
		)
		(fp_line
			(start 0.12065 0.3048)
			(end 0.67945 0.3048)
			(stroke
				(width 0.1)
				(type default)
			)
			(layer "B.Fab")
		)
		(fp_line
			(start 0.67945 0.3048)
			(end 0.67945 -0.305054)
			(stroke
				(width 0.1)
				(type default)
			)
			(layer "B.Fab")
		)
		(fp_line
			(start -0.120396 0.2794)
			(end 0.12065 0.2794)
			(stroke
				(width 0.1)
				(type default)
			)
			(layer "B.Fab")
		)
		(fp_line
			(start 0.12065 0.2794)
			(end 0.12065 0.3048)
			(stroke
				(width 0.1)
				(type default)
			)
			(layer "B.Fab")
		)
		(fp_line
			(start -0.12065 -0.2794)
			(end -0.12065 -0.3048)
			(stroke
				(width 0.1)
				(type default)
			)
			(layer "B.Fab")
		)
		(fp_line
			(start 0.12065 -0.2794)
			(end -0.12065 -0.2794)
			(stroke
				(width 0.1)
				(type default)
			)
			(layer "B.Fab")
		)
		(fp_line
			(start -0.67945 -0.3048)
			(end -0.67945 0.3048)
			(stroke
				(width 0.1)
				(type default)
			)
			(layer "B.Fab")
		)
		(fp_line
			(start -0.12065 -0.3048)
			(end -0.67945 -0.3048)
			(stroke
				(width 0.1)
				(type default)
			)
			(layer "B.Fab")
		)
		(fp_line
			(start 0.12065 -0.305054)
			(end 0.12065 -0.2794)
			(stroke
				(width 0.1)
				(type default)
			)
			(layer "B.Fab")
		)
		(fp_line
			(start 0.67945 -0.305054)
			(end 0.12065 -0.305054)
			(stroke
				(width 0.1)
				(type default)
			)
			(layer "B.Fab")
		)
		(pad "1" smd circle
			(at 0.40005 0 90)
			(size 0 0)
			(layers "B.Cu" "B.Mask" "B.Paste")
			(net "PVDDCR_CPU1_P1_VOS2")
		)
		(pad "2" smd circle
			(at -0.40005 0 90)
			(size 0 0)
			(layers "B.Cu" "B.Mask" "B.Paste")
			(net "PVDDCR_CPU1_P1")
		)
	)
	(footprint ""
		(layer "B.Cu")
		(at 436.997348 -19.07667 -90)
		(property "Reference" "R1898"
			(at 0 0 90)
			(layer "B.SilkS")
			(hide yes)
			(effects
				(font
					(size 1.27 1.27)
				)
				(justify mirror)
			)
		)
		(property "Value" ""
			(at 0 0 90)
			(layer "B.Fab")
			(effects
				(font
					(size 1.27 1.27)
				)
				(justify mirror)
			)
		)
		(duplicate_pad_numbers_are_jumpers no)
		(fp_line
			(start -0.7874 0.4064)
			(end 0.7874 0.4064)
			(stroke
				(width 0.1524)
				(type default)
			)
			(layer "B.SilkS")
		)
		(fp_line
			(start 0.7874 0.4064)
			(end 0.7874 -0.4064)
			(stroke
				(width 0.1524)
				(type default)
			)
			(layer "B.SilkS")
		)
		(fp_line
			(start -0.7874 -0.4064)
			(end -0.7874 0.4064)
			(stroke
				(width 0.1524)
				(type default)
			)
			(layer "B.SilkS")
		)
		(fp_line
			(start 0.7874 -0.4064)
			(end -0.7874 -0.4064)
			(stroke
				(width 0.1524)
				(type default)
			)
			(layer "B.SilkS")
		)
		(fp_line
			(start -0.67945 0.3048)
			(end -0.120396 0.3048)
			(stroke
				(width 0.1)
				(type default)
			)
			(layer "B.Fab")
		)
		(fp_line
			(start -0.120396 0.3048)
			(end -0.120396 0.2794)
			(stroke
				(width 0.1)
				(type default)
			)
			(layer "B.Fab")
		)
		(fp_line
			(start 0.12065 0.3048)
			(end 0.67945 0.3048)
			(stroke
				(width 0.1)
				(type default)
			)
			(layer "B.Fab")
		)
		(fp_line
			(start 0.67945 0.3048)
			(end 0.67945 -0.305054)
			(stroke
				(width 0.1)
				(type default)
			)
			(layer "B.Fab")
		)
		(fp_line
			(start -0.120396 0.2794)
			(end 0.12065 0.2794)
			(stroke
				(width 0.1)
				(type default)
			)
			(layer "B.Fab")
		)
		(fp_line
			(start 0.12065 0.2794)
			(end 0.12065 0.3048)
			(stroke
				(width 0.1)
				(type default)
			)
			(layer "B.Fab")
		)
		(fp_line
			(start -0.12065 -0.2794)
			(end -0.12065 -0.3048)
			(stroke
				(width 0.1)
				(type default)
			)
			(layer "B.Fab")
		)
		(fp_line
			(start 0.12065 -0.2794)
			(end -0.12065 -0.2794)
			(stroke
				(width 0.1)
				(type default)
			)
			(layer "B.Fab")
		)
		(fp_line
			(start -0.67945 -0.3048)
			(end -0.67945 0.3048)
			(stroke
				(width 0.1)
				(type default)
			)
			(layer "B.Fab")
		)
		(fp_line
			(start -0.12065 -0.3048)
			(end -0.67945 -0.3048)
			(stroke
				(width 0.1)
				(type default)
			)
			(layer "B.Fab")
		)
		(fp_line
			(start 0.12065 -0.305054)
			(end 0.12065 -0.2794)
			(stroke
				(width 0.1)
				(type default)
			)
			(layer "B.Fab")
		)
		(fp_line
			(start 0.67945 -0.305054)
			(end 0.12065 -0.305054)
			(stroke
				(width 0.1)
				(type default)
			)
			(layer "B.Fab")
		)
		(pad "1" smd circle
			(at 0.40005 0 90)
			(size 0 0)
			(layers "B.Cu" "B.Mask" "B.Paste")
			(net "OCP_SFF_ISO_BIF2_EN")
		)
		(pad "2" smd circle
			(at -0.40005 0 90)
			(size 0 0)
			(layers "B.Cu" "B.Mask" "B.Paste")
			(net "GND")
		)
	)
)
